# T6G (Grand Teton) — schematic netlist excerpt (pin names and nets, part order shuffled) for the footprints in the layout excerpt that follows; sources: Cadence DE-HDL packaged netlist, KiCad conversion of 04192023_DAF0TMB3IC0_F0TG_MB_C_brd_V02_OCP.brd

X2  TP_TDR_4P_FTS  TP_TDR_4P_DIP EMPTY  pkg TH  page 260
  S1  = TDR_DIFF_80_IN1_DP
  P1  = T1_GND
  P2  = T1_GND
  S2  = TDR_DIFF_80_IN1_DN

PL8064  Q_INDUCTOR  BLM18SN220TN1D/8000MA IND  pkg SMLF  page 189 : \1\ = P12V_AUX ; \2\ = SW_P5V_AUX_FLT

(kicad_pcb
	(version 20260206)
	(generator "pcbnew")
	(generator_version "10.0")
	(general
		(thickness 1.6)
		(legacy_teardrops no)
	)
	(paper "A4")
	(title_block
		(title "04192023_DAF0TMB3IC0_F0TG_MB_C_brd_V02_OCP.brd")
		(comment 1 "Grand Teton / footprints 459-460 of 8354")
	)
	(layers
		(0 "F.Cu" signal "TOP")
		(4 "In1.Cu" signal "GND")
		(6 "In2.Cu" signal "IN1")
		(8 "In3.Cu" signal "GND1")
		(10 "In4.Cu" signal "IN2")
		(12 "In5.Cu" signal "GND2")
		(14 "In6.Cu" signal "IN3")
		(16 "In7.Cu" signal "GND3")
		(18 "In8.Cu" signal "VCC")
		(20 "In9.Cu" signal "VCC1")
		(22 "In10.Cu" signal "GND4")
		(24 "In11.Cu" signal "IN4")
		(26 "In12.Cu" signal "GND5")
		(28 "In13.Cu" signal "IN5")
		(30 "In14.Cu" signal "GND6")
		(32 "In15.Cu" signal "IN6")
		(34 "In16.Cu" signal "GND7")
		(2 "B.Cu" signal "BOTTOM")
		(9 "F.Adhes" user "F.Adhesive")
		(11 "B.Adhes" user "B.Adhesive")
		(13 "F.Paste" user "Package Geometry/Pastemask Top")
		(15 "B.Paste" user "Package Geometry/Pastemask Bottom")
		(5 "F.SilkS" user "Ref Des/Silkscreen Top")
		(7 "B.SilkS" user "Ref Des/Silkscreen Bottom")
		(1 "F.Mask" user "Board Geometry/Soldermask Top")
		(3 "B.Mask" user "Board Geometry/Soldermask Bottom")
		(17 "Dwgs.User" user "User.Drawings")
		(19 "Cmts.User" user "User.Comments")
		(21 "Eco1.User" user "User.Eco1")
		(23 "Eco2.User" user "User.Eco2")
		(25 "Edge.Cuts" user "Board Geometry/Outline")
		(27 "Margin" user)
		(31 "F.CrtYd" user "Package Geometry/Place Bound Top")
		(29 "B.CrtYd" user "Package Geometry/Place Bound Bottom")
		(35 "F.Fab" user "Ref Des/Assembly Top")
		(33 "B.Fab" user "Ref Des/Assembly Bottom")
	)
	(footprint ""
		(layer "F.Cu")
		(at 517.258808 -147.972526 -90)
		(property "Reference" "X2"
			(at -1.903222 3.256788 0)
			(unlocked yes)
			(layer "F.SilkS")
			(effects
				(font
					(size 0.7874 0.5842)
					(thickness 0.1524)
				)
				(justify left)
			)
		)
		(property "Value" ""
			(at 0 0 270)
			(layer "F.Fab")
			(effects
				(font
					(size 1.27 1.27)
				)
			)
		)
		(property "Device Type" "TP_TDR_4P_FTS_TH-TP_TDR_4P_DIP,EMPTY,TP15"
			(at 1.30175 1.27 0)
			(unlocked yes)
			(layer "F.Fab")
			(hide yes)
			(effects
				(font
					(size 0.635 0.4064)
					(thickness 0.1524)
				)
			)
		)
		(property "User Part Number" "N_A"
			(at 1.30175 1.27 0)
			(unlocked yes)
			(layer "Cmts.User")
			(hide yes)
			(effects
				(font
					(size 0.635 0.4064)
					(thickness 0.1524)
				)
			)
		)
		(duplicate_pad_numbers_are_jumpers no)
		(fp_line
			(start 0 3.81)
			(end 2.54 3.81)
			(stroke
				(width 0.1524)
				(type default)
			)
			(layer "F.SilkS")
		)
		(fp_line
			(start 2.54 3.81)
			(end 2.54 3.6703)
			(stroke
				(width 0.1524)
				(type default)
			)
			(layer "F.SilkS")
		)
		(fp_line
			(start 0 3.175)
			(end 0 3.81)
			(stroke
				(width 0.1524)
				(type default)
			)
			(layer "F.SilkS")
		)
		(fp_line
			(start 2.54 1.4097)
			(end 2.54 1.1303)
			(stroke
				(width 0.1524)
				(type default)
			)
			(layer "F.SilkS")
		)
		(fp_line
			(start 0 0.635)
			(end 0 1.905)
			(stroke
				(width 0.1524)
				(type default)
			)
			(layer "F.SilkS")
		)
		(fp_line
			(start 2.54 -1.1303)
			(end 2.54 -1.27)
			(stroke
				(width 0.1524)
				(type default)
			)
			(layer "F.SilkS")
		)
		(fp_line
			(start 0 -1.27)
			(end 0 -0.635)
			(stroke
				(width 0.1524)
				(type default)
			)
			(layer "F.SilkS")
		)
		(fp_line
			(start 2.54 -1.27)
			(end 0 -1.27)
			(stroke
				(width 0.1524)
				(type default)
			)
			(layer "F.SilkS")
		)
		(fp_poly
			(pts
				(xy -0.761746 0) (xy -2.285746 0.762) (xy -2.285746 -0.762)
			)
			(stroke
				(width 0)
				(type default)
			)
			(fill yes)
			(layer "F.SilkS")
		)
		(fp_line
			(start 0 3.81)
			(end 2.54 3.81)
			(stroke
				(width 0.1)
				(type default)
			)
			(layer "F.Fab")
		)
		(fp_line
			(start 2.54 3.81)
			(end 2.54 -1.27)
			(stroke
				(width 0.1)
				(type default)
			)
			(layer "F.Fab")
		)
		(fp_line
			(start 0 -1.27)
			(end 0 3.81)
			(stroke
				(width 0.1)
				(type default)
			)
			(layer "F.Fab")
		)
		(fp_line
			(start 2.54 -1.27)
			(end 0 -1.27)
			(stroke
				(width 0.1)
				(type default)
			)
			(layer "F.Fab")
		)
		(fp_poly
			(pts
				(xy -0.761746 0) (xy -2.285746 -0.762) (xy -2.285746 0.762)
			)
			(stroke
				(width 0)
				(type default)
			)
			(fill yes)
			(layer "F.Fab")
		)
		(pad "1" thru_hole circle
			(at 0 0 270)
			(size 1.0033 1.0033)
			(drill 0.249936)
			(layers "*.Cu" "*.Mask")
			(remove_unused_layers no)
			(net "TDR_DIFF_80_IN1_DP")
			(clearance 0.10795)
			(thermal_gap 0.10795)
			(padstack
				(mode front_inner_back)
				(layer "Inner"
					(shape circle)
					(size 0.8001 0.8001)
					(clearance 0.1524)
				)
				(layer "B.Cu"
					(shape circle)
					(size 1.0033 1.0033)
					(clearance 0.10795)
				)
			)
		)
		(pad "2" thru_hole circle
			(at 2.54 0 270)
			(size 1.9939 1.9939)
			(drill 0.249936)
			(layers "*.Cu" "*.Mask")
			(remove_unused_layers no)
			(net "T1_GND")
			(clearance 0.10795)
			(thermal_gap 0.10795)
			(padstack
				(mode front_inner_back)
				(layer "Inner"
					(shape circle)
					(size 0.8001 0.8001)
					(clearance 0.1524)
				)
				(layer "B.Cu"
					(shape circle)
					(size 1.9939 1.9939)
					(clearance 0.10795)
				)
			)
		)
		(pad "3" thru_hole circle
			(at 2.54 2.54 270)
			(size 1.9939 1.9939)
			(drill 0.249936)
			(layers "*.Cu" "*.Mask")
			(remove_unused_layers no)
			(net "T1_GND")
			(clearance 0.10795)
			(thermal_gap 0.10795)
			(padstack
				(mode front_inner_back)
				(layer "Inner"
					(shape circle)
					(size 0.8001 0.8001)
					(clearance 0.1524)
				)
				(layer "B.Cu"
					(shape circle)
					(size 1.9939 1.9939)
					(clearance 0.10795)
				)
			)
		)
		(pad "4" thru_hole circle
			(at 0 2.54 270)
			(size 1.0033 1.0033)
			(drill 0.249936)
			(layers "*.Cu" "*.Mask")
			(remove_unused_layers no)
			(net "TDR_DIFF_80_IN1_DN")
			(clearance 0.10795)
			(thermal_gap 0.10795)
			(padstack
				(mode front_inner_back)
				(layer "Inner"
					(shape circle)
					(size 0.8001 0.8001)
					(clearance 0.1524)
				)
				(layer "B.Cu"
					(shape circle)
					(size 1.0033 1.0033)
					(clearance 0.10795)
				)
			)
		)
	)
	(footprint ""
		(layer "F.Cu")
		(at 410.936186 -133.594348)
		(property "Reference" "PL8064"
			(at 0 0 0)
			(layer "F.SilkS")
			(hide yes)
			(effects
				(font
					(size 1.27 1.27)
				)
			)
		)
		(property "Value" ""
			(at 0 0 0)
			(layer "F.Fab")
			(effects
				(font
					(size 1.27 1.27)
				)
			)
		)
		(duplicate_pad_numbers_are_jumpers no)
		(fp_line
			(start -1.27 -0.5842)
			(end 1.27 -0.5842)
			(stroke
				(width 0.1524)
				(type default)
			)
			(layer "F.SilkS")
		)
		(fp_line
			(start -1.27 -0.5588)
			(end -1.27 -0.5842)
			(stroke
				(width 0.1524)
				(type default)
			)
			(layer "F.SilkS")
		)
		(fp_line
			(start -1.27 0.5842)
			(end -1.27 -0.5842)
			(stroke
				(width 0.1524)
				(type default)
			)
			(layer "F.SilkS")
		)
		(fp_line
			(start 1.27 0.5842)
			(end -1.27 0.5842)
			(stroke
				(width 0.1524)
				(type default)
			)
			(layer "F.SilkS")
		)
		(fp_line
			(start 1.27 0.5842)
			(end 1.27 -0.5842)
			(stroke
				(width 0.1524)
				(type default)
			)
			(layer "F.SilkS")
		)
		(fp_line
			(start -1.194308 -0.406654)
			(end -0.9144 -0.406654)
			(stroke
				(width 0.1)
				(type default)
			)
			(layer "F.Fab")
		)
		(fp_line
			(start -1.194308 0.406654)
			(end -1.194308 -0.406654)
			(stroke
				(width 0.1)
				(type default)
			)
			(layer "F.Fab")
		)
		(fp_line
			(start -0.9144 -0.508)
			(end 0.9144 -0.508)
			(stroke
				(width 0.1)
				(type default)
			)
			(layer "F.Fab")
		)
		(fp_line
			(start -0.9144 -0.406654)
			(end -0.9144 -0.508)
			(stroke
				(width 0.1)
				(type default)
			)
			(layer "F.Fab")
		)
		(fp_line
			(start -0.9144 0.406654)
			(end -1.194308 0.406654)
			(stroke
				(width 0.1)
				(type default)
			)
			(layer "F.Fab")
		)
		(fp_line
			(start -0.9144 0.508)
			(end -0.9144 0.406654)
			(stroke
				(width 0.1)
				(type default)
			)
			(layer "F.Fab")
		)
		(fp_line
			(start 0.9144 -0.508)
			(end 0.9144 -0.406654)
			(stroke
				(width 0.1)
				(type default)
			)
			(layer "F.Fab")
		)
		(fp_line
			(start 0.9144 -0.406654)
			(end 1.1938 -0.406654)
			(stroke
				(width 0.1)
				(type default)
			)
			(layer "F.Fab")
		)
		(fp_line
			(start 0.9144 0.4064)
			(end 0.9144 0.508)
			(stroke
				(width 0.1)
				(type default)
			)
			(layer "F.Fab")
		)
		(fp_line
			(start 0.9144 0.508)
			(end -0.9144 0.508)
			(stroke
				(width 0.1)
				(type default)
			)
			(layer "F.Fab")
		)
		(fp_line
			(start 1.1938 -0.406654)
			(end 1.1938 0.4064)
			(stroke
				(width 0.1)
				(type default)
			)
			(layer "F.Fab")
		)
		(fp_line
			(start 1.1938 0.4064)
			(end 0.9144 0.4064)
			(stroke
				(width 0.1)
				(type default)
			)
			(layer "F.Fab")
		)
		(pad "1" smd rect
			(at -0.7366 0 270)
			(size 0.7112 0.8128)
			(layers "F.Cu" "F.Mask" "F.Paste")
			(net "P12V_AUX")
		)
		(pad "2" smd rect
			(at 0.7366 0 270)
			(size 0.7112 0.8128)
			(layers "F.Cu" "F.Mask" "F.Paste")
			(net "SW_P5V_AUX_FLT")
		)
	)
)
